# T6G (Grand Teton) — schematic netlist excerpt (pin names and nets, part order shuffled) for the footprints in the layout excerpt that follows; sources: Cadence DE-HDL packaged netlist, KiCad conversion of 04192023_DAF0TMB3IC0_F0TG_MB_C_brd_V02_OCP.brd

R9025  Q_RES  100K 1% EMPTY  pkg 0402LF  page 85 : A = IRQ_HSC_FAULT_N ; B = GND
C2078  Q_CAP_DIFFBUS  DIFF BUS_0.22UF 6.3V 20% X6S  pkg C0201  page 26 : \1\ = P2E_CPU0_P5_TX_DN ; \2\ = P2E_CPU0_P5_TX_C_DN
R334  Q_RES  100K 1% CHIP  pkg 0402LF  page 188 : A = VR_P5V_EN ; B = GND

(kicad_pcb
	(version 20260206)
	(generator "pcbnew")
	(generator_version "10.0")
	(general
		(thickness 1.6)
		(legacy_teardrops no)
	)
	(paper "A4")
	(title_block
		(title "04192023_DAF0TMB3IC0_F0TG_MB_C_brd_V02_OCP.brd")
		(comment 1 "Grand Teton / footprints 4221-4223 of 8354")
	)
	(layers
		(0 "F.Cu" signal "TOP")
		(4 "In1.Cu" signal "GND")
		(6 "In2.Cu" signal "IN1")
		(8 "In3.Cu" signal "GND1")
		(10 "In4.Cu" signal "IN2")
		(12 "In5.Cu" signal "GND2")
		(14 "In6.Cu" signal "IN3")
		(16 "In7.Cu" signal "GND3")
		(18 "In8.Cu" signal "VCC")
		(20 "In9.Cu" signal "VCC1")
		(22 "In10.Cu" signal "GND4")
		(24 "In11.Cu" signal "IN4")
		(26 "In12.Cu" signal "GND5")
		(28 "In13.Cu" signal "IN5")
		(30 "In14.Cu" signal "GND6")
		(32 "In15.Cu" signal "IN6")
		(34 "In16.Cu" signal "GND7")
		(2 "B.Cu" signal "BOTTOM")
		(9 "F.Adhes" user "F.Adhesive")
		(11 "B.Adhes" user "B.Adhesive")
		(13 "F.Paste" user "Package Geometry/Pastemask Top")
		(15 "B.Paste" user "Package Geometry/Pastemask Bottom")
		(5 "F.SilkS" user "Ref Des/Silkscreen Top")
		(7 "B.SilkS" user "Ref Des/Silkscreen Bottom")
		(1 "F.Mask" user "Board Geometry/Soldermask Top")
		(3 "B.Mask" user "Board Geometry/Soldermask Bottom")
		(17 "Dwgs.User" user "User.Drawings")
		(19 "Cmts.User" user "User.Comments")
		(21 "Eco1.User" user "User.Eco1")
		(23 "Eco2.User" user "User.Eco2")
		(25 "Edge.Cuts" user "Board Geometry/Outline")
		(27 "Margin" user)
		(31 "F.CrtYd" user "Package Geometry/Place Bound Top")
		(29 "B.CrtYd" user "Package Geometry/Place Bound Bottom")
		(35 "F.Fab" user "Ref Des/Assembly Top")
		(33 "B.Fab" user "Ref Des/Assembly Bottom")
	)
	(footprint ""
		(layer "F.Cu")
		(at 162.052 -105.918 -90)
		(property "Reference" "R9025"
			(at 0 0 270)
			(layer "F.SilkS")
			(hide yes)
			(effects
				(font
					(size 1.27 1.27)
				)
			)
		)
		(property "Value" ""
			(at 0 0 270)
			(layer "F.Fab")
			(effects
				(font
					(size 1.27 1.27)
				)
			)
		)
		(duplicate_pad_numbers_are_jumpers no)
		(fp_line
			(start -0.7874 0.4064)
			(end -0.7874 -0.4064)
			(stroke
				(width 0.1524)
				(type default)
			)
			(layer "F.SilkS")
		)
		(fp_line
			(start 0.7874 0.4064)
			(end -0.7874 0.4064)
			(stroke
				(width 0.1524)
				(type default)
			)
			(layer "F.SilkS")
		)
		(fp_line
			(start -0.7874 -0.4064)
			(end 0.7874 -0.4064)
			(stroke
				(width 0.1524)
				(type default)
			)
			(layer "F.SilkS")
		)
		(fp_line
			(start 0.7874 -0.4064)
			(end 0.7874 0.4064)
			(stroke
				(width 0.1524)
				(type default)
			)
			(layer "F.SilkS")
		)
		(fp_line
			(start -0.67945 0.3048)
			(end -0.67945 -0.305054)
			(stroke
				(width 0.1)
				(type default)
			)
			(layer "F.Fab")
		)
		(fp_line
			(start -0.12065 0.3048)
			(end -0.67945 0.3048)
			(stroke
				(width 0.1)
				(type default)
			)
			(layer "F.Fab")
		)
		(fp_line
			(start 0.120396 0.3048)
			(end 0.120396 0.2794)
			(stroke
				(width 0.1)
				(type default)
			)
			(layer "F.Fab")
		)
		(fp_line
			(start 0.67945 0.3048)
			(end 0.120396 0.3048)
			(stroke
				(width 0.1)
				(type default)
			)
			(layer "F.Fab")
		)
		(fp_line
			(start -0.12065 0.2794)
			(end -0.12065 0.3048)
			(stroke
				(width 0.1)
				(type default)
			)
			(layer "F.Fab")
		)
		(fp_line
			(start 0.120396 0.2794)
			(end -0.12065 0.2794)
			(stroke
				(width 0.1)
				(type default)
			)
			(layer "F.Fab")
		)
		(fp_line
			(start -0.12065 -0.2794)
			(end 0.12065 -0.2794)
			(stroke
				(width 0.1)
				(type default)
			)
			(layer "F.Fab")
		)
		(fp_line
			(start 0.12065 -0.2794)
			(end 0.12065 -0.3048)
			(stroke
				(width 0.1)
				(type default)
			)
			(layer "F.Fab")
		)
		(fp_line
			(start 0.12065 -0.3048)
			(end 0.67945 -0.3048)
			(stroke
				(width 0.1)
				(type default)
			)
			(layer "F.Fab")
		)
		(fp_line
			(start 0.67945 -0.3048)
			(end 0.67945 0.3048)
			(stroke
				(width 0.1)
				(type default)
			)
			(layer "F.Fab")
		)
		(fp_line
			(start -0.67945 -0.305054)
			(end -0.12065 -0.305054)
			(stroke
				(width 0.1)
				(type default)
			)
			(layer "F.Fab")
		)
		(fp_line
			(start -0.12065 -0.305054)
			(end -0.12065 -0.2794)
			(stroke
				(width 0.1)
				(type default)
			)
			(layer "F.Fab")
		)
		(pad "1" smd circle
			(at -0.40005 0 270)
			(size 0 0)
			(layers "F.Cu" "F.Mask" "F.Paste")
			(net "IRQ_HSC_FAULT_N")
		)
		(pad "2" smd circle
			(at 0.40005 0 270)
			(size 0 0)
			(layers "F.Cu" "F.Mask" "F.Paste")
			(net "GND")
		)
	)
	(footprint ""
		(layer "F.Cu")
		(at 148.494242 -107.683046)
		(property "Reference" "R334"
			(at 0 0 0)
			(layer "F.SilkS")
			(hide yes)
			(effects
				(font
					(size 1.27 1.27)
				)
			)
		)
		(property "Value" ""
			(at 0 0 0)
			(layer "F.Fab")
			(effects
				(font
					(size 1.27 1.27)
				)
			)
		)
		(duplicate_pad_numbers_are_jumpers no)
		(fp_line
			(start -0.7874 -0.4064)
			(end 0.7874 -0.4064)
			(stroke
				(width 0.1524)
				(type default)
			)
			(layer "F.SilkS")
		)
		(fp_line
			(start -0.7874 0.4064)
			(end -0.7874 -0.4064)
			(stroke
				(width 0.1524)
				(type default)
			)
			(layer "F.SilkS")
		)
		(fp_line
			(start 0.7874 -0.4064)
			(end 0.7874 0.4064)
			(stroke
				(width 0.1524)
				(type default)
			)
			(layer "F.SilkS")
		)
		(fp_line
			(start 0.7874 0.4064)
			(end -0.7874 0.4064)
			(stroke
				(width 0.1524)
				(type default)
			)
			(layer "F.SilkS")
		)
		(fp_line
			(start -0.67945 -0.305054)
			(end -0.12065 -0.305054)
			(stroke
				(width 0.1)
				(type default)
			)
			(layer "F.Fab")
		)
		(fp_line
			(start -0.67945 0.3048)
			(end -0.67945 -0.305054)
			(stroke
				(width 0.1)
				(type default)
			)
			(layer "F.Fab")
		)
		(fp_line
			(start -0.12065 -0.305054)
			(end -0.12065 -0.2794)
			(stroke
				(width 0.1)
				(type default)
			)
			(layer "F.Fab")
		)
		(fp_line
			(start -0.12065 -0.2794)
			(end 0.12065 -0.2794)
			(stroke
				(width 0.1)
				(type default)
			)
			(layer "F.Fab")
		)
		(fp_line
			(start -0.12065 0.2794)
			(end -0.12065 0.3048)
			(stroke
				(width 0.1)
				(type default)
			)
			(layer "F.Fab")
		)
		(fp_line
			(start -0.12065 0.3048)
			(end -0.67945 0.3048)
			(stroke
				(width 0.1)
				(type default)
			)
			(layer "F.Fab")
		)
		(fp_line
			(start 0.120396 0.2794)
			(end -0.12065 0.2794)
			(stroke
				(width 0.1)
				(type default)
			)
			(layer "F.Fab")
		)
		(fp_line
			(start 0.120396 0.3048)
			(end 0.120396 0.2794)
			(stroke
				(width 0.1)
				(type default)
			)
			(layer "F.Fab")
		)
		(fp_line
			(start 0.12065 -0.3048)
			(end 0.67945 -0.3048)
			(stroke
				(width 0.1)
				(type default)
			)
			(layer "F.Fab")
		)
		(fp_line
			(start 0.12065 -0.2794)
			(end 0.12065 -0.3048)
			(stroke
				(width 0.1)
				(type default)
			)
			(layer "F.Fab")
		)
		(fp_line
			(start 0.67945 -0.3048)
			(end 0.67945 0.3048)
			(stroke
				(width 0.1)
				(type default)
			)
			(layer "F.Fab")
		)
		(fp_line
			(start 0.67945 0.3048)
			(end 0.120396 0.3048)
			(stroke
				(width 0.1)
				(type default)
			)
			(layer "F.Fab")
		)
		(pad "1" smd circle
			(at -0.40005 0)
			(size 0 0)
			(layers "F.Cu" "F.Mask" "F.Paste")
			(net "VR_P5V_EN")
		)
		(pad "2" smd circle
			(at 0.40005 0)
			(size 0 0)
			(layers "F.Cu" "F.Mask" "F.Paste")
			(net "GND")
		)
	)
	(footprint ""
		(layer "F.Cu")
		(at 160.856422 -20.068794 -90)
		(property "Reference" "C2078"
			(at 0 0 270)
			(layer "F.SilkS")
			(hide yes)
			(effects
				(font
					(size 1.27 1.27)
				)
			)
		)
		(property "Value" ""
			(at 0 0 270)
			(layer "F.Fab")
			(effects
				(font
					(size 1.27 1.27)
				)
			)
		)
		(duplicate_pad_numbers_are_jumpers no)
		(fp_line
			(start -0.299974 0.150114)
			(end -0.299974 -0.150114)
			(stroke
				(width 0.1)
				(type default)
			)
			(layer "F.Fab")
		)
		(fp_line
			(start 0.299974 0.150114)
			(end -0.299974 0.150114)
			(stroke
				(width 0.1)
				(type default)
			)
			(layer "F.Fab")
		)
		(fp_line
			(start -0.299974 -0.150114)
			(end 0.299974 -0.150114)
			(stroke
				(width 0.1)
				(type default)
			)
			(layer "F.Fab")
		)
		(fp_line
			(start 0.299974 -0.150114)
			(end 0.299974 0.150114)
			(stroke
				(width 0.1)
				(type default)
			)
			(layer "F.Fab")
		)
		(pad "1" smd rect
			(at -0.2667 0 270)
			(size 0.3048 0.381)
			(layers "F.Cu" "F.Mask" "F.Paste")
			(net "P2E_CPU0_P5_TX_DN")
		)
		(pad "2" smd rect
			(at 0.2667 0 270)
			(size 0.3048 0.381)
			(layers "F.Cu" "F.Mask" "F.Paste")
			(net "P2E_CPU0_P5_TX_C_DN")
		)
	)
)
